(kicad_pcb
	(version 20260206)
	(generator "pcbnew")
	(generator_version "10.0")
	(general
		(thickness 1.6)
		(legacy_teardrops no)
	)
	(paper "A4")
	(title_block
		(title "03242023_DA0F0TMBIJ0_F0T_Motherboard_J_brd_V01_OCP.brd")
		(comment 1 "Grand Teton / footprints 5686-5692 of 6105")
	)
	(layers
		(0 "F.Cu" signal "TOP")
		(4 "In1.Cu" signal "GND")
		(6 "In2.Cu" signal "IN1")
		(8 "In3.Cu" signal "GND1")
		(10 "In4.Cu" signal "IN2")
		(12 "In5.Cu" signal "GND2")
		(14 "In6.Cu" signal "IN3")
		(16 "In7.Cu" signal "GND3")
		(18 "In8.Cu" signal "VCC")
		(20 "In9.Cu" signal "VCC1")
		(22 "In10.Cu" signal "GND4")
		(24 "In11.Cu" signal "IN4")
		(26 "In12.Cu" signal "GND5")
		(28 "In13.Cu" signal "IN5")
		(30 "In14.Cu" signal "GND6")
		(32 "In15.Cu" signal "IN6")
		(34 "In16.Cu" signal "GND7")
		(2 "B.Cu" signal "BOTTOM")
		(9 "F.Adhes" user "F.Adhesive")
		(11 "B.Adhes" user "B.Adhesive")
		(13 "F.Paste" user "Package Geometry/Pastemask Top")
		(15 "B.Paste" user "Package Geometry/Pastemask Bottom")
		(5 "F.SilkS" user "Ref Des/Silkscreen Top")
		(7 "B.SilkS" user "Ref Des/Silkscreen Bottom")
		(1 "F.Mask" user "Board Geometry/Soldermask Top")
		(3 "B.Mask" user "Board Geometry/Soldermask Bottom")
		(17 "Dwgs.User" user "User.Drawings")
		(19 "Cmts.User" user "User.Comments")
		(21 "Eco1.User" user "User.Eco1")
		(23 "Eco2.User" user "User.Eco2")
		(25 "Edge.Cuts" user "Board Geometry/Outline")
		(27 "Margin" user)
		(31 "F.CrtYd" user "Package Geometry/Place Bound Top")
		(29 "B.CrtYd" user "Package Geometry/Place Bound Bottom")
		(35 "F.Fab" user "Ref Des/Assembly Top")
		(33 "B.Fab" user "Ref Des/Assembly Bottom")
	)
	(footprint ""
		(layer "B.Cu")
		(at 105.679494 -244.82044 -90)
		(property "Reference" "C316"
			(at 0 0 90)
			(layer "B.SilkS")
			(hide yes)
			(effects
				(font
					(size 1.27 1.27)
				)
				(justify mirror)
			)
		)
		(property "Value" ""
			(at 0 0 90)
			(layer "B.Fab")
			(effects
				(font
					(size 1.27 1.27)
				)
				(justify mirror)
			)
		)
		(duplicate_pad_numbers_are_jumpers no)
		(fp_line
			(start -1.524 0.762)
			(end 1.524 0.762)
			(stroke
				(width 0.1524)
				(type default)
			)
			(layer "B.SilkS")
		)
		(fp_line
			(start 1.524 0.762)
			(end 1.524 -0.762)
			(stroke
				(width 0.1524)
				(type default)
			)
			(layer "B.SilkS")
		)
		(fp_line
			(start -1.524 -0.762)
			(end -1.524 0.762)
			(stroke
				(width 0.1524)
				(type default)
			)
			(layer "B.SilkS")
		)
		(fp_line
			(start 1.524 -0.762)
			(end -1.524 -0.762)
			(stroke
				(width 0.1524)
				(type default)
			)
			(layer "B.SilkS")
		)
		(fp_line
			(start -1.1049 0.724916)
			(end -1.1049 -0.724916)
			(stroke
				(width 0.1)
				(type default)
			)
			(layer "B.Fab")
		)
		(fp_line
			(start 1.1049 0.724916)
			(end -1.1049 0.724916)
			(stroke
				(width 0.1)
				(type default)
			)
			(layer "B.Fab")
		)
		(fp_line
			(start -1.1049 -0.724916)
			(end 1.1049 -0.724916)
			(stroke
				(width 0.1)
				(type default)
			)
			(layer "B.Fab")
		)
		(fp_line
			(start 1.1049 -0.724916)
			(end 1.1049 0.724916)
			(stroke
				(width 0.1)
				(type default)
			)
			(layer "B.Fab")
		)
		(pad "1" smd rect
			(at 0.889 0 270)
			(size 1.016 1.27)
			(layers "B.Cu" "B.Mask" "B.Paste")
			(net "PVCCIN_CPU1")
		)
		(pad "2" smd rect
			(at -0.889 0 270)
			(size 1.016 1.27)
			(layers "B.Cu" "B.Mask" "B.Paste")
			(net "GND")
		)
	)
	(footprint ""
		(layer "B.Cu")
		(at 179.85994 -21.364448 -90)
		(property "Reference" "R4511"
			(at 0 0 90)
			(layer "B.SilkS")
			(hide yes)
			(effects
				(font
					(size 1.27 1.27)
				)
				(justify mirror)
			)
		)
		(property "Value" ""
			(at 0 0 90)
			(layer "B.Fab")
			(effects
				(font
					(size 1.27 1.27)
				)
				(justify mirror)
			)
		)
		(duplicate_pad_numbers_are_jumpers no)
		(fp_line
			(start -0.7874 0.4064)
			(end 0.7874 0.4064)
			(stroke
				(width 0.1524)
				(type default)
			)
			(layer "B.SilkS")
		)
		(fp_line
			(start 0.7874 0.4064)
			(end 0.7874 -0.4064)
			(stroke
				(width 0.1524)
				(type default)
			)
			(layer "B.SilkS")
		)
		(fp_line
			(start -0.7874 -0.4064)
			(end -0.7874 0.4064)
			(stroke
				(width 0.1524)
				(type default)
			)
			(layer "B.SilkS")
		)
		(fp_line
			(start 0.7874 -0.4064)
			(end -0.7874 -0.4064)
			(stroke
				(width 0.1524)
				(type default)
			)
			(layer "B.SilkS")
		)
		(fp_line
			(start -0.67945 0.3048)
			(end -0.120396 0.3048)
			(stroke
				(width 0.1)
				(type default)
			)
			(layer "B.Fab")
		)
		(fp_line
			(start -0.120396 0.3048)
			(end -0.120396 0.2794)
			(stroke
				(width 0.1)
				(type default)
			)
			(layer "B.Fab")
		)
		(fp_line
			(start 0.12065 0.3048)
			(end 0.67945 0.3048)
			(stroke
				(width 0.1)
				(type default)
			)
			(layer "B.Fab")
		)
		(fp_line
			(start 0.67945 0.3048)
			(end 0.67945 -0.305054)
			(stroke
				(width 0.1)
				(type default)
			)
			(layer "B.Fab")
		)
		(fp_line
			(start -0.120396 0.2794)
			(end 0.12065 0.2794)
			(stroke
				(width 0.1)
				(type default)
			)
			(layer "B.Fab")
		)
		(fp_line
			(start 0.12065 0.2794)
			(end 0.12065 0.3048)
			(stroke
				(width 0.1)
				(type default)
			)
			(layer "B.Fab")
		)
		(fp_line
			(start -0.12065 -0.2794)
			(end -0.12065 -0.3048)
			(stroke
				(width 0.1)
				(type default)
			)
			(layer "B.Fab")
		)
		(fp_line
			(start 0.12065 -0.2794)
			(end -0.12065 -0.2794)
			(stroke
				(width 0.1)
				(type default)
			)
			(layer "B.Fab")
		)
		(fp_line
			(start -0.67945 -0.3048)
			(end -0.67945 0.3048)
			(stroke
				(width 0.1)
				(type default)
			)
			(layer "B.Fab")
		)
		(fp_line
			(start -0.12065 -0.3048)
			(end -0.67945 -0.3048)
			(stroke
				(width 0.1)
				(type default)
			)
			(layer "B.Fab")
		)
		(fp_line
			(start 0.12065 -0.305054)
			(end 0.12065 -0.2794)
			(stroke
				(width 0.1)
				(type default)
			)
			(layer "B.Fab")
		)
		(fp_line
			(start 0.67945 -0.305054)
			(end 0.12065 -0.305054)
			(stroke
				(width 0.1)
				(type default)
			)
			(layer "B.Fab")
		)
		(pad "1" smd circle
			(at 0.40005 0 90)
			(size 0 0)
			(layers "B.Cu" "B.Mask" "B.Paste")
			(net "SMB_HOST_3V3AUX_SDA")
		)
		(pad "2" smd circle
			(at -0.40005 0 90)
			(size 0 0)
			(layers "B.Cu" "B.Mask" "B.Paste")
			(net "SMB_HOST_3V3AUX_SDA_R4")
		)
	)
	(footprint ""
		(layer "B.Cu")
		(at 410.492956 -318.908176 90)
		(property "Reference" "R886"
			(at 0 0 90)
			(layer "B.SilkS")
			(hide yes)
			(effects
				(font
					(size 1.27 1.27)
				)
				(justify mirror)
			)
		)
		(property "Value" ""
			(at 0 0 90)
			(layer "B.Fab")
			(effects
				(font
					(size 1.27 1.27)
				)
				(justify mirror)
			)
		)
		(duplicate_pad_numbers_are_jumpers no)
		(fp_line
			(start 0.7874 -0.4064)
			(end -0.7874 -0.4064)
			(stroke
				(width 0.1524)
				(type default)
			)
			(layer "B.SilkS")
		)
		(fp_line
			(start -0.7874 -0.4064)
			(end -0.7874 0.4064)
			(stroke
				(width 0.1524)
				(type default)
			)
			(layer "B.SilkS")
		)
		(fp_line
			(start 0.7874 0.4064)
			(end 0.7874 -0.4064)
			(stroke
				(width 0.1524)
				(type default)
			)
			(layer "B.SilkS")
		)
		(fp_line
			(start -0.7874 0.4064)
			(end 0.7874 0.4064)
			(stroke
				(width 0.1524)
				(type default)
			)
			(layer "B.SilkS")
		)
		(fp_line
			(start 0.67945 -0.305054)
			(end 0.12065 -0.305054)
			(stroke
				(width 0.1)
				(type default)
			)
			(layer "B.Fab")
		)
		(fp_line
			(start 0.12065 -0.305054)
			(end 0.12065 -0.2794)
			(stroke
				(width 0.1)
				(type default)
			)
			(layer "B.Fab")
		)
		(fp_line
			(start -0.12065 -0.3048)
			(end -0.67945 -0.3048)
			(stroke
				(width 0.1)
				(type default)
			)
			(layer "B.Fab")
		)
		(fp_line
			(start -0.67945 -0.3048)
			(end -0.67945 0.3048)
			(stroke
				(width 0.1)
				(type default)
			)
			(layer "B.Fab")
		)
		(fp_line
			(start 0.12065 -0.2794)
			(end -0.12065 -0.2794)
			(stroke
				(width 0.1)
				(type default)
			)
			(layer "B.Fab")
		)
		(fp_line
			(start -0.12065 -0.2794)
			(end -0.12065 -0.3048)
			(stroke
				(width 0.1)
				(type default)
			)
			(layer "B.Fab")
		)
		(fp_line
			(start 0.12065 0.2794)
			(end 0.12065 0.3048)
			(stroke
				(width 0.1)
				(type default)
			)
			(layer "B.Fab")
		)
		(fp_line
			(start -0.120396 0.2794)
			(end 0.12065 0.2794)
			(stroke
				(width 0.1)
				(type default)
			)
			(layer "B.Fab")
		)
		(fp_line
			(start 0.67945 0.3048)
			(end 0.67945 -0.305054)
			(stroke
				(width 0.1)
				(type default)
			)
			(layer "B.Fab")
		)
		(fp_line
			(start 0.12065 0.3048)
			(end 0.67945 0.3048)
			(stroke
				(width 0.1)
				(type default)
			)
			(layer "B.Fab")
		)
		(fp_line
			(start -0.120396 0.3048)
			(end -0.120396 0.2794)
			(stroke
				(width 0.1)
				(type default)
			)
			(layer "B.Fab")
		)
		(fp_line
			(start -0.67945 0.3048)
			(end -0.120396 0.3048)
			(stroke
				(width 0.1)
				(type default)
			)
			(layer "B.Fab")
		)
		(pad "1" smd circle
			(at 0.40005 0 270)
			(size 0 0)
			(layers "B.Cu" "B.Mask" "B.Paste")
			(net "PWRGD_CHE_CPU0_DIMM2")
		)
		(pad "2" smd circle
			(at -0.40005 0 270)
			(size 0 0)
			(layers "B.Cu" "B.Mask" "B.Paste")
			(net "PWRGD_FAIL_CPU0_EF")
		)
	)
	(footprint ""
		(layer "B.Cu")
		(at 38.015926 -344.935556 -90)
		(property "Reference" "PC1209_P1_4"
			(at 0 0 90)
			(layer "B.SilkS")
			(hide yes)
			(effects
				(font
					(size 1.27 1.27)
				)
				(justify mirror)
			)
		)
		(property "Value" ""
			(at 0 0 90)
			(layer "B.Fab")
			(effects
				(font
					(size 1.27 1.27)
				)
				(justify mirror)
			)
		)
		(duplicate_pad_numbers_are_jumpers no)
		(fp_line
			(start -1.524 0.762)
			(end 1.524 0.762)
			(stroke
				(width 0.1524)
				(type default)
			)
			(layer "B.SilkS")
		)
		(fp_line
			(start 1.524 0.762)
			(end 1.524 -0.762)
			(stroke
				(width 0.1524)
				(type default)
			)
			(layer "B.SilkS")
		)
		(fp_line
			(start -1.524 -0.762)
			(end -1.524 0.762)
			(stroke
				(width 0.1524)
				(type default)
			)
			(layer "B.SilkS")
		)
		(fp_line
			(start 1.524 -0.762)
			(end -1.524 -0.762)
			(stroke
				(width 0.1524)
				(type default)
			)
			(layer "B.SilkS")
		)
		(fp_line
			(start -1.1049 0.724916)
			(end -1.1049 -0.724916)
			(stroke
				(width 0.1)
				(type default)
			)
			(layer "B.Fab")
		)
		(fp_line
			(start 1.1049 0.724916)
			(end -1.1049 0.724916)
			(stroke
				(width 0.1)
				(type default)
			)
			(layer "B.Fab")
		)
		(fp_line
			(start -1.1049 -0.724916)
			(end 1.1049 -0.724916)
			(stroke
				(width 0.1)
				(type default)
			)
			(layer "B.Fab")
		)
		(fp_line
			(start 1.1049 -0.724916)
			(end 1.1049 0.724916)
			(stroke
				(width 0.1)
				(type default)
			)
			(layer "B.Fab")
		)
		(pad "1" smd rect
			(at 0.889 0 270)
			(size 1.016 1.27)
			(layers "B.Cu" "B.Mask" "B.Paste")
			(net "PVCCFA_EHV_FIVRA_CPU1")
		)
		(pad "2" smd rect
			(at -0.889 0 270)
			(size 1.016 1.27)
			(layers "B.Cu" "B.Mask" "B.Paste")
			(net "GND")
		)
	)
	(footprint ""
		(layer "B.Cu")
		(at 230.249222 -121.743216 -90)
		(property "Reference" "L3"
			(at 0 0 90)
			(layer "B.SilkS")
			(hide yes)
			(effects
				(font
					(size 1.27 1.27)
				)
				(justify mirror)
			)
		)
		(property "Value" ""
			(at 0 0 90)
			(layer "B.Fab")
			(effects
				(font
					(size 1.27 1.27)
				)
				(justify mirror)
			)
		)
		(duplicate_pad_numbers_are_jumpers no)
		(fp_line
			(start -1.27 0.5842)
			(end 1.27 0.5842)
			(stroke
				(width 0.1524)
				(type default)
			)
			(layer "B.SilkS")
		)
		(fp_line
			(start -1.27 0.5842)
			(end -1.27 -0.5842)
			(stroke
				(width 0.1524)
				(type default)
			)
			(layer "B.SilkS")
		)
		(fp_line
			(start -0.127 0.5842)
			(end -0.127 -0.5842)
			(stroke
				(width 0.1524)
				(type default)
			)
			(layer "B.SilkS")
		)
		(fp_line
			(start 0.127 0.5842)
			(end 0.127 -0.5842)
			(stroke
				(width 0.1524)
				(type default)
			)
			(layer "B.SilkS")
		)
		(fp_line
			(start 1.27 0.5842)
			(end 1.27 -0.5842)
			(stroke
				(width 0.1524)
				(type default)
			)
			(layer "B.SilkS")
		)
		(fp_line
			(start 1.27 -0.5588)
			(end 1.27 -0.5842)
			(stroke
				(width 0.1524)
				(type default)
			)
			(layer "B.SilkS")
		)
		(fp_line
			(start 1.27 -0.5842)
			(end -1.27 -0.5842)
			(stroke
				(width 0.1524)
				(type default)
			)
			(layer "B.SilkS")
		)
		(fp_line
			(start -0.9144 0.508)
			(end 0.9144 0.508)
			(stroke
				(width 0.1)
				(type default)
			)
			(layer "B.Fab")
		)
		(fp_line
			(start 0.9144 0.508)
			(end 0.9144 0.406654)
			(stroke
				(width 0.1)
				(type default)
			)
			(layer "B.Fab")
		)
		(fp_line
			(start 0.9144 0.406654)
			(end 1.194308 0.406654)
			(stroke
				(width 0.1)
				(type default)
			)
			(layer "B.Fab")
		)
		(fp_line
			(start 1.194308 0.406654)
			(end 1.194308 -0.406654)
			(stroke
				(width 0.1)
				(type default)
			)
			(layer "B.Fab")
		)
		(fp_line
			(start -1.1938 0.4064)
			(end -0.9144 0.4064)
			(stroke
				(width 0.1)
				(type default)
			)
			(layer "B.Fab")
		)
		(fp_line
			(start -0.9144 0.4064)
			(end -0.9144 0.508)
			(stroke
				(width 0.1)
				(type default)
			)
			(layer "B.Fab")
		)
		(fp_line
			(start -1.1938 -0.406654)
			(end -1.1938 0.4064)
			(stroke
				(width 0.1)
				(type default)
			)
			(layer "B.Fab")
		)
		(fp_line
			(start -0.9144 -0.406654)
			(end -1.1938 -0.406654)
			(stroke
				(width 0.1)
				(type default)
			)
			(layer "B.Fab")
		)
		(fp_line
			(start 0.9144 -0.406654)
			(end 0.9144 -0.508)
			(stroke
				(width 0.1)
				(type default)
			)
			(layer "B.Fab")
		)
		(fp_line
			(start 1.194308 -0.406654)
			(end 0.9144 -0.406654)
			(stroke
				(width 0.1)
				(type default)
			)
			(layer "B.Fab")
		)
		(fp_line
			(start -0.9144 -0.508)
			(end -0.9144 -0.406654)
			(stroke
				(width 0.1)
				(type default)
			)
			(layer "B.Fab")
		)
		(fp_line
			(start 0.9144 -0.508)
			(end -0.9144 -0.508)
			(stroke
				(width 0.1)
				(type default)
			)
			(layer "B.Fab")
		)
		(pad "1" smd rect
			(at 0.7366 0 180)
			(size 0.7112 0.8128)
			(layers "B.Cu" "B.Mask" "B.Paste")
			(net "P3V3")
		)
		(pad "2" smd rect
			(at -0.7366 0 180)
			(size 0.7112 0.8128)
			(layers "B.Cu" "B.Mask" "B.Paste")
			(net "P3V3_DB2000_VDD")
		)
	)
	(footprint ""
		(layer "B.Cu")
		(at 236.62513 -48.104044)
		(property "Reference" "C1283"
			(at 0 0 0)
			(layer "B.SilkS")
			(hide yes)
			(effects
				(font
					(size 1.27 1.27)
				)
				(justify mirror)
			)
		)
		(property "Value" ""
			(at 0 0 0)
			(layer "B.Fab")
			(effects
				(font
					(size 1.27 1.27)
				)
				(justify mirror)
			)
		)
		(duplicate_pad_numbers_are_jumpers no)
		(fp_line
			(start -0.7874 -0.4064)
			(end -0.7874 0.4064)
			(stroke
				(width 0.1524)
				(type default)
			)
			(layer "B.SilkS")
		)
		(fp_line
			(start -0.7874 0.4064)
			(end 0.7874 0.4064)
			(stroke
				(width 0.1524)
				(type default)
			)
			(layer "B.SilkS")
		)
		(fp_line
			(start 0.7874 -0.4064)
			(end -0.7874 -0.4064)
			(stroke
				(width 0.1524)
				(type default)
			)
			(layer "B.SilkS")
		)
		(fp_line
			(start 0.7874 0.4064)
			(end 0.7874 -0.4064)
			(stroke
				(width 0.1524)
				(type default)
			)
			(layer "B.SilkS")
		)
		(fp_line
			(start -0.67945 -0.3048)
			(end -0.67945 0.3048)
			(stroke
				(width 0.1)
				(type default)
			)
			(layer "B.Fab")
		)
		(fp_line
			(start -0.67945 0.3048)
			(end -0.120396 0.3048)
			(stroke
				(width 0.1)
				(type default)
			)
			(layer "B.Fab")
		)
		(fp_line
			(start -0.12065 -0.3048)
			(end -0.67945 -0.3048)
			(stroke
				(width 0.1)
				(type default)
			)
			(layer "B.Fab")
		)
		(fp_line
			(start -0.12065 -0.2794)
			(end -0.12065 -0.3048)
			(stroke
				(width 0.1)
				(type default)
			)
			(layer "B.Fab")
		)
		(fp_line
			(start -0.120396 0.2794)
			(end 0.12065 0.2794)
			(stroke
				(width 0.1)
				(type default)
			)
			(layer "B.Fab")
		)
		(fp_line
			(start -0.120396 0.3048)
			(end -0.120396 0.2794)
			(stroke
				(width 0.1)
				(type default)
			)
			(layer "B.Fab")
		)
		(fp_line
			(start 0.12065 -0.305054)
			(end 0.12065 -0.2794)
			(stroke
				(width 0.1)
				(type default)
			)
			(layer "B.Fab")
		)
		(fp_line
			(start 0.12065 -0.2794)
			(end -0.12065 -0.2794)
			(stroke
				(width 0.1)
				(type default)
			)
			(layer "B.Fab")
		)
		(fp_line
			(start 0.12065 0.2794)
			(end 0.12065 0.3048)
			(stroke
				(width 0.1)
				(type default)
			)
			(layer "B.Fab")
		)
		(fp_line
			(start 0.12065 0.3048)
			(end 0.67945 0.3048)
			(stroke
				(width 0.1)
				(type default)
			)
			(layer "B.Fab")
		)
		(fp_line
			(start 0.67945 -0.305054)
			(end 0.12065 -0.305054)
			(stroke
				(width 0.1)
				(type default)
			)
			(layer "B.Fab")
		)
		(fp_line
			(start 0.67945 0.3048)
			(end 0.67945 -0.305054)
			(stroke
				(width 0.1)
				(type default)
			)
			(layer "B.Fab")
		)
		(pad "1" smd circle
			(at 0.40005 0 180)
			(size 0 0)
			(layers "B.Cu" "B.Mask" "B.Paste")
			(net "P3V3_E1S_0")
		)
		(pad "2" smd circle
			(at -0.40005 0 180)
			(size 0 0)
			(layers "B.Cu" "B.Mask" "B.Paste")
			(net "GND")
		)
	)
	(footprint ""
		(layer "B.Cu")
		(at 334.744314 -33.173162 90)
		(property "Reference" "R918"
			(at 0 0 90)
			(layer "B.SilkS")
			(hide yes)
			(effects
				(font
					(size 1.27 1.27)
				)
				(justify mirror)
			)
		)
		(property "Value" ""
			(at 0 0 90)
			(layer "B.Fab")
			(effects
				(font
					(size 1.27 1.27)
				)
				(justify mirror)
			)
		)
		(duplicate_pad_numbers_are_jumpers no)
		(fp_line
			(start 0.7874 -0.4064)
			(end -0.7874 -0.4064)
			(stroke
				(width 0.1524)
				(type default)
			)
			(layer "B.SilkS")
		)
		(fp_line
			(start -0.7874 -0.4064)
			(end -0.7874 0.4064)
			(stroke
				(width 0.1524)
				(type default)
			)
			(layer "B.SilkS")
		)
		(fp_line
			(start 0.7874 0.4064)
			(end 0.7874 -0.4064)
			(stroke
				(width 0.1524)
				(type default)
			)
			(layer "B.SilkS")
		)
		(fp_line
			(start -0.7874 0.4064)
			(end 0.7874 0.4064)
			(stroke
				(width 0.1524)
				(type default)
			)
			(layer "B.SilkS")
		)
		(fp_line
			(start 0.67945 -0.305054)
			(end 0.12065 -0.305054)
			(stroke
				(width 0.1)
				(type default)
			)
			(layer "B.Fab")
		)
		(fp_line
			(start 0.12065 -0.305054)
			(end 0.12065 -0.2794)
			(stroke
				(width 0.1)
				(type default)
			)
			(layer "B.Fab")
		)
		(fp_line
			(start -0.12065 -0.3048)
			(end -0.67945 -0.3048)
			(stroke
				(width 0.1)
				(type default)
			)
			(layer "B.Fab")
		)
		(fp_line
			(start -0.67945 -0.3048)
			(end -0.67945 0.3048)
			(stroke
				(width 0.1)
				(type default)
			)
			(layer "B.Fab")
		)
		(fp_line
			(start 0.12065 -0.2794)
			(end -0.12065 -0.2794)
			(stroke
				(width 0.1)
				(type default)
			)
			(layer "B.Fab")
		)
		(fp_line
			(start -0.12065 -0.2794)
			(end -0.12065 -0.3048)
			(stroke
				(width 0.1)
				(type default)
			)
			(layer "B.Fab")
		)
		(fp_line
			(start 0.12065 0.2794)
			(end 0.12065 0.3048)
			(stroke
				(width 0.1)
				(type default)
			)
			(layer "B.Fab")
		)
		(fp_line
			(start -0.120396 0.2794)
			(end 0.12065 0.2794)
			(stroke
				(width 0.1)
				(type default)
			)
			(layer "B.Fab")
		)
		(fp_line
			(start 0.67945 0.3048)
			(end 0.67945 -0.305054)
			(stroke
				(width 0.1)
				(type default)
			)
			(layer "B.Fab")
		)
		(fp_line
			(start 0.12065 0.3048)
			(end 0.67945 0.3048)
			(stroke
				(width 0.1)
				(type default)
			)
			(layer "B.Fab")
		)
		(fp_line
			(start -0.120396 0.3048)
			(end -0.120396 0.2794)
			(stroke
				(width 0.1)
				(type default)
			)
			(layer "B.Fab")
		)
		(fp_line
			(start -0.67945 0.3048)
			(end -0.120396 0.3048)
			(stroke
				(width 0.1)
				(type default)
			)
			(layer "B.Fab")
		)
		(pad "1" smd circle
			(at 0.40005 0 270)
			(size 0 0)
			(layers "B.Cu" "B.Mask" "B.Paste")
			(net "SPI_PCH_IO2")
		)
		(pad "2" smd circle
			(at -0.40005 0 270)
			(size 0 0)
			(layers "B.Cu" "B.Mask" "B.Paste")
			(net "SPI_SYS_WP_IO2")
		)
	)
)
